#ISCELL
  mstr_misc dns *
  *
#ISCELL
  pure_quanta quanta_title_block_c *
  *
#ISCELL
  standard offpage *
  page218_i1
#ISCELL
  standard offpage *
  page218_i10
#ISCELL
  standard offpage *
  page218_i11
#CELL
  pure_quanta qs3vh257qg8 *
  page218_i12
#ISCELL
  standard offpage *
  page218_i13
#ISCELL
  standard offpage *
  page218_i14
#ISCELL
  standard offpage *
  page218_i15
#ISCELL
  standard offpage *
  page218_i16
#CELL
  pure_quanta q_res *
  page218_i17
#CELL
  pure_quanta q_res *
  page218_i18
#ISCELL
  logical_power universal_power *
  page218_i19
#ISCELL
  standard offpage *
  page218_i2
#CELL
  pure_quanta q_res *
  page218_i20
#CELL
  pure_quanta q_res *
  page218_i21
#CELL
  pure_quanta q_res *
  page218_i22
#CELL
  pure_quanta q_res *
  page218_i23
#ISCELL
  logical_power universal_gnd *
  page218_i24
#CELL
  pure_quanta q_cap *
  page218_i25
#ISCELL
  logical_power universal_gnd *
  page218_i26
#ISCELL
  logical_power universal_power *
  page218_i27
#CELL
  pure_quanta q_res *
  page218_i28
#CELL
  pure_quanta q_res *
  page218_i29
#ISCELL
  logical_power universal_gnd *
  page218_i3
#CELL
  pure_quanta q_res *
  page218_i30
#CELL
  pure_quanta q_res *
  page218_i31
#CELL
  pure_quanta q_res *
  page218_i32
#CELL
  pure_quanta q_res *
  page218_i33
#CELL
  pure_quanta q_res *
  page218_i34
#CELL
  pure_quanta q_res *
  page218_i35
#CELL
  pure_quanta q_res *
  page218_i36
#CELL
  pure_quanta q_res *
  page218_i37
#ISCELL
  standard offpage *
  page218_i38
#ISCELL
  standard offpage *
  page218_i39
#CELL
  pure_quanta q_res *
  page218_i4
#ISCELL
  standard offpage *
  page218_i40
#ISCELL
  standard offpage *
  page218_i41
#ISCELL
  standard offpage *
  page218_i42
#ISCELL
  standard offpage *
  page218_i43
#ISCELL
  standard offpage *
  page218_i44
#ISCELL
  standard offpage *
  page218_i45
#ISCELL
  standard offpage *
  page218_i5
#ISCELL
  standard offpage *
  page218_i6
#ISCELL
  standard offpage *
  page218_i7
#ISCELL
  standard offpage *
  page218_i8
#ISCELL
  standard offpage *
  page218_i9
